# T6G (Grand Teton) — schematic netlist excerpt (pin names and nets, part order shuffled) for the footprints in the layout excerpt that follows; sources: Cadence DE-HDL packaged netlist, KiCad conversion of 04192023_DAF0TMB3IC0_F0TG_MB_C_brd_V02_OCP.brd

TP11  TP  NA  pkg TP  page 54 : TP = VSENSE_VSS_SENSE_A_P1
R926  Q_RES  4.7K 5% EMPTY  pkg 0201LF  page 353 : A = MODE_RT_CPU1_P3 ; B = GND
R450  Q_RES  4.7K 5% CHIP  pkg 0402LF  page 28 : A = CPU0_SMERR_N ; B = PVDD18_S5_P0
PC308_C0P1_5  Q_CAP  2.2UF 10V 10% X6S  pkg C0402  page 213 : A = PVDDCR_CPU0_P1_PVCC ; B = GND

(kicad_pcb
	(version 20260206)
	(generator "pcbnew")
	(generator_version "10.0")
	(general
		(thickness 1.6)
		(legacy_teardrops no)
	)
	(paper "A4")
	(title_block
		(title "04192023_DAF0TMB3IC0_F0TG_MB_C_brd_V02_OCP.brd")
		(comment 1 "Grand Teton / footprints 3107-3110 of 8354")
	)
	(layers
		(0 "F.Cu" signal "TOP")
		(4 "In1.Cu" signal "GND")
		(6 "In2.Cu" signal "IN1")
		(8 "In3.Cu" signal "GND1")
		(10 "In4.Cu" signal "IN2")
		(12 "In5.Cu" signal "GND2")
		(14 "In6.Cu" signal "IN3")
		(16 "In7.Cu" signal "GND3")
		(18 "In8.Cu" signal "VCC")
		(20 "In9.Cu" signal "VCC1")
		(22 "In10.Cu" signal "GND4")
		(24 "In11.Cu" signal "IN4")
		(26 "In12.Cu" signal "GND5")
		(28 "In13.Cu" signal "IN5")
		(30 "In14.Cu" signal "GND6")
		(32 "In15.Cu" signal "IN6")
		(34 "In16.Cu" signal "GND7")
		(2 "B.Cu" signal "BOTTOM")
		(9 "F.Adhes" user "F.Adhesive")
		(11 "B.Adhes" user "B.Adhesive")
		(13 "F.Paste" user "Package Geometry/Pastemask Top")
		(15 "B.Paste" user "Package Geometry/Pastemask Bottom")
		(5 "F.SilkS" user "Ref Des/Silkscreen Top")
		(7 "B.SilkS" user "Ref Des/Silkscreen Bottom")
		(1 "F.Mask" user "Board Geometry/Soldermask Top")
		(3 "B.Mask" user "Board Geometry/Soldermask Bottom")
		(17 "Dwgs.User" user "User.Drawings")
		(19 "Cmts.User" user "User.Comments")
		(21 "Eco1.User" user "User.Eco1")
		(23 "Eco2.User" user "User.Eco2")
		(25 "Edge.Cuts" user "Board Geometry/Outline")
		(27 "Margin" user)
		(31 "F.CrtYd" user "Package Geometry/Place Bound Top")
		(29 "B.CrtYd" user "Package Geometry/Place Bound Bottom")
		(35 "F.Fab" user "Ref Des/Assembly Top")
		(33 "B.Fab" user "Ref Des/Assembly Bottom")
	)
	(footprint ""
		(layer "F.Cu")
		(at 393.363958 -324.659752)
		(property "Reference" "R450"
			(at 0 0 0)
			(layer "F.SilkS")
			(hide yes)
			(effects
				(font
					(size 1.27 1.27)
				)
			)
		)
		(property "Value" ""
			(at 0 0 0)
			(layer "F.Fab")
			(effects
				(font
					(size 1.27 1.27)
				)
			)
		)
		(duplicate_pad_numbers_are_jumpers no)
		(fp_line
			(start -0.7874 -0.4064)
			(end 0.7874 -0.4064)
			(stroke
				(width 0.1524)
				(type default)
			)
			(layer "F.SilkS")
		)
		(fp_line
			(start -0.7874 0.4064)
			(end -0.7874 -0.4064)
			(stroke
				(width 0.1524)
				(type default)
			)
			(layer "F.SilkS")
		)
		(fp_line
			(start 0.7874 -0.4064)
			(end 0.7874 0.4064)
			(stroke
				(width 0.1524)
				(type default)
			)
			(layer "F.SilkS")
		)
		(fp_line
			(start 0.7874 0.4064)
			(end -0.7874 0.4064)
			(stroke
				(width 0.1524)
				(type default)
			)
			(layer "F.SilkS")
		)
		(fp_line
			(start -0.67945 -0.305054)
			(end -0.12065 -0.305054)
			(stroke
				(width 0.1)
				(type default)
			)
			(layer "F.Fab")
		)
		(fp_line
			(start -0.67945 0.3048)
			(end -0.67945 -0.305054)
			(stroke
				(width 0.1)
				(type default)
			)
			(layer "F.Fab")
		)
		(fp_line
			(start -0.12065 -0.305054)
			(end -0.12065 -0.2794)
			(stroke
				(width 0.1)
				(type default)
			)
			(layer "F.Fab")
		)
		(fp_line
			(start -0.12065 -0.2794)
			(end 0.12065 -0.2794)
			(stroke
				(width 0.1)
				(type default)
			)
			(layer "F.Fab")
		)
		(fp_line
			(start -0.12065 0.2794)
			(end -0.12065 0.3048)
			(stroke
				(width 0.1)
				(type default)
			)
			(layer "F.Fab")
		)
		(fp_line
			(start -0.12065 0.3048)
			(end -0.67945 0.3048)
			(stroke
				(width 0.1)
				(type default)
			)
			(layer "F.Fab")
		)
		(fp_line
			(start 0.120396 0.2794)
			(end -0.12065 0.2794)
			(stroke
				(width 0.1)
				(type default)
			)
			(layer "F.Fab")
		)
		(fp_line
			(start 0.120396 0.3048)
			(end 0.120396 0.2794)
			(stroke
				(width 0.1)
				(type default)
			)
			(layer "F.Fab")
		)
		(fp_line
			(start 0.12065 -0.3048)
			(end 0.67945 -0.3048)
			(stroke
				(width 0.1)
				(type default)
			)
			(layer "F.Fab")
		)
		(fp_line
			(start 0.12065 -0.2794)
			(end 0.12065 -0.3048)
			(stroke
				(width 0.1)
				(type default)
			)
			(layer "F.Fab")
		)
		(fp_line
			(start 0.67945 -0.3048)
			(end 0.67945 0.3048)
			(stroke
				(width 0.1)
				(type default)
			)
			(layer "F.Fab")
		)
		(fp_line
			(start 0.67945 0.3048)
			(end 0.120396 0.3048)
			(stroke
				(width 0.1)
				(type default)
			)
			(layer "F.Fab")
		)
		(pad "1" smd circle
			(at -0.40005 0)
			(size 0 0)
			(layers "F.Cu" "F.Mask" "F.Paste")
			(net "CPU0_SMERR_N")
		)
		(pad "2" smd circle
			(at 0.40005 0)
			(size 0 0)
			(layers "F.Cu" "F.Mask" "F.Paste")
			(net "PVDD18_S5_P0")
		)
	)
	(footprint ""
		(layer "F.Cu")
		(at 141.197838 -167.03167)
		(property "Reference" "TP11"
			(at 1.13792 -0.014732 0)
			(unlocked yes)
			(layer "F.SilkS")
			(effects
				(font
					(size 0.7874 0.5842)
					(thickness 0.1524)
				)
				(justify left)
			)
		)
		(property "Value" ""
			(at 0 0 0)
			(layer "F.Fab")
			(effects
				(font
					(size 1.27 1.27)
				)
			)
		)
		(duplicate_pad_numbers_are_jumpers no)
		(pad "1" smd circle
			(at 0 0)
			(size 0.762 0.762)
			(layers "F.Cu" "F.Mask" "F.Paste")
			(net "VSENSE_VSS_SENSE_A_P1")
		)
	)
	(footprint ""
		(layer "F.Cu")
		(at 112.72774 -394.166852 -90)
		(property "Reference" "R926"
			(at 0 0 270)
			(layer "F.SilkS")
			(hide yes)
			(effects
				(font
					(size 1.27 1.27)
				)
			)
		)
		(property "Value" ""
			(at 0 0 270)
			(layer "F.Fab")
			(effects
				(font
					(size 1.27 1.27)
				)
			)
		)
		(duplicate_pad_numbers_are_jumpers no)
		(fp_line
			(start -0.32512 0.175006)
			(end -0.32512 -0.175006)
			(stroke
				(width 0.1)
				(type default)
			)
			(layer "F.Fab")
		)
		(fp_line
			(start 0.32512 0.175006)
			(end -0.32512 0.175006)
			(stroke
				(width 0.1)
				(type default)
			)
			(layer "F.Fab")
		)
		(fp_line
			(start -0.32512 -0.175006)
			(end 0.32512 -0.175006)
			(stroke
				(width 0.1)
				(type default)
			)
			(layer "F.Fab")
		)
		(fp_line
			(start 0.32512 -0.175006)
			(end 0.32512 0.175006)
			(stroke
				(width 0.1)
				(type default)
			)
			(layer "F.Fab")
		)
		(pad "1" smd rect
			(at -0.2667 0 270)
			(size 0.3048 0.381)
			(layers "F.Cu" "F.Mask" "F.Paste")
			(net "MODE_RT_CPU1_P3")
		)
		(pad "2" smd rect
			(at 0.2667 0 90)
			(size 0.3048 0.381)
			(layers "F.Cu" "F.Mask" "F.Paste")
			(net "GND")
		)
	)
	(footprint ""
		(layer "F.Cu")
		(at 77.64399 -177.627534 90)
		(property "Reference" "PC308_C0P1_5"
			(at 0 0 90)
			(layer "F.SilkS")
			(hide yes)
			(effects
				(font
					(size 1.27 1.27)
				)
			)
		)
		(property "Value" ""
			(at 0 0 90)
			(layer "F.Fab")
			(effects
				(font
					(size 1.27 1.27)
				)
			)
		)
		(duplicate_pad_numbers_are_jumpers no)
		(fp_line
			(start 0.7874 -0.4064)
			(end 0.7874 0.4064)
			(stroke
				(width 0.1524)
				(type default)
			)
			(layer "F.SilkS")
		)
		(fp_line
			(start -0.7874 -0.4064)
			(end 0.7874 -0.4064)
			(stroke
				(width 0.1524)
				(type default)
			)
			(layer "F.SilkS")
		)
		(fp_line
			(start 0.7874 0.4064)
			(end -0.7874 0.4064)
			(stroke
				(width 0.1524)
				(type default)
			)
			(layer "F.SilkS")
		)
		(fp_line
			(start -0.7874 0.4064)
			(end -0.7874 -0.4064)
			(stroke
				(width 0.1524)
				(type default)
			)
			(layer "F.SilkS")
		)
		(fp_line
			(start -0.12065 -0.305054)
			(end -0.12065 -0.2794)
			(stroke
				(width 0.1)
				(type default)
			)
			(layer "F.Fab")
		)
		(fp_line
			(start -0.67945 -0.305054)
			(end -0.12065 -0.305054)
			(stroke
				(width 0.1)
				(type default)
			)
			(layer "F.Fab")
		)
		(fp_line
			(start 0.67945 -0.3048)
			(end 0.67945 0.3048)
			(stroke
				(width 0.1)
				(type default)
			)
			(layer "F.Fab")
		)
		(fp_line
			(start 0.12065 -0.3048)
			(end 0.67945 -0.3048)
			(stroke
				(width 0.1)
				(type default)
			)
			(layer "F.Fab")
		)
		(fp_line
			(start 0.12065 -0.2794)
			(end 0.12065 -0.3048)
			(stroke
				(width 0.1)
				(type default)
			)
			(layer "F.Fab")
		)
		(fp_line
			(start -0.12065 -0.2794)
			(end 0.12065 -0.2794)
			(stroke
				(width 0.1)
				(type default)
			)
			(layer "F.Fab")
		)
		(fp_line
			(start 0.120396 0.2794)
			(end -0.12065 0.2794)
			(stroke
				(width 0.1)
				(type default)
			)
			(layer "F.Fab")
		)
		(fp_line
			(start -0.12065 0.2794)
			(end -0.12065 0.3048)
			(stroke
				(width 0.1)
				(type default)
			)
			(layer "F.Fab")
		)
		(fp_line
			(start 0.67945 0.3048)
			(end 0.120396 0.3048)
			(stroke
				(width 0.1)
				(type default)
			)
			(layer "F.Fab")
		)
		(fp_line
			(start 0.120396 0.3048)
			(end 0.120396 0.2794)
			(stroke
				(width 0.1)
				(type default)
			)
			(layer "F.Fab")
		)
		(fp_line
			(start -0.12065 0.3048)
			(end -0.67945 0.3048)
			(stroke
				(width 0.1)
				(type default)
			)
			(layer "F.Fab")
		)
		(fp_line
			(start -0.67945 0.3048)
			(end -0.67945 -0.305054)
			(stroke
				(width 0.1)
				(type default)
			)
			(layer "F.Fab")
		)
		(pad "1" smd circle
			(at -0.40005 0 90)
			(size 0 0)
			(layers "F.Cu" "F.Mask" "F.Paste")
			(net "PVDDCR_CPU0_P1_PVCC")
		)
		(pad "2" smd circle
			(at 0.40005 0 90)
			(size 0 0)
			(layers "F.Cu" "F.Mask" "F.Paste")
			(net "GND")
		)
	)
)
